(kicad_pcb
	(version 20241229)
	(generator "pcbnew")
	(generator_version "9.0")
	(general
		(thickness 1.62)
		(legacy_teardrops no)
	)
	(paper "A3")
	(title_block
		(title "COM Express 7 Baseboard")
		(date "2025-02-04")
		(rev "1.1.2")
		(company "Antmicro Ltd")
		(comment 1 "www.antmicro.com")
		(comment 9 "footprints 478-480 of 802")
	)
	(layers
		(0 "F.Cu" signal)
		(4 "In1.Cu" signal)
		(6 "In2.Cu" signal)
		(8 "In3.Cu" signal)
		(10 "In4.Cu" signal)
		(12 "In5.Cu" signal)
		(14 "In6.Cu" signal)
		(2 "B.Cu" signal)
		(9 "F.Adhes" user "F.Adhesive")
		(11 "B.Adhes" user "B.Adhesive")
		(13 "F.Paste" user)
		(15 "B.Paste" user)
		(5 "F.SilkS" user "F.Silkscreen")
		(7 "B.SilkS" user "B.Silkscreen")
		(1 "F.Mask" user)
		(3 "B.Mask" user)
		(17 "Dwgs.User" user "User.Drawings")
		(19 "Cmts.User" user "User.Comments")
		(21 "Eco1.User" user "User.Eco1")
		(23 "Eco2.User" user "User.Eco2")
		(25 "Edge.Cuts" user)
		(27 "Margin" user)
		(31 "F.CrtYd" user "F.Courtyard")
		(29 "B.CrtYd" user "B.Courtyard")
		(35 "F.Fab" user)
		(33 "B.Fab" user)
	)
	(footprint "antmicro-footprints:LED_0603_1608Metric_G"
		(layer "F.Cu")
		(at 199.70861 74.802163 90)
		(descr "LED SMD 0603 Green")
		(tags "LED SMD 0603 Green")
		(property "Reference" "D27"
			(at -1.1 -0.55 90)
			(layer "F.SilkS")
			(effects
				(font
					(size 0.7 0.7)
					(thickness 0.15)
				)
				(justify left bottom)
			)
		)
		(property "Value" "LED_G_0603_LTST-C190GKT"
			(at -0.001 1.599 90)
			(layer "F.Fab")
			(effects
				(font
					(size 0.7 0.7)
					(thickness 0.15)
				)
				(justify left bottom)
			)
		)
		(property "Datasheet" "https://media.digikey.com/pdf/Data%20Sheets/Lite-On%20PDFs/LTST-C190GKT.pdf"
			(at 0 0 90)
			(layer "F.Fab")
			(hide yes)
			(effects
				(font
					(size 1.27 1.27)
					(thickness 0.15)
				)
			)
		)
		(property "Author" "Antmicro"
			(at 274.510773 -124.906447 0)
			(layer "F.Fab")
			(hide yes)
			(effects
				(font
					(size 1 1)
					(thickness 0.15)
				)
			)
		)
		(property "Color" "Green"
			(at 274.510773 -124.906447 0)
			(layer "F.Fab")
			(hide yes)
			(effects
				(font
					(size 1 1)
					(thickness 0.15)
				)
			)
		)
		(property "License" "Apache-2.0"
			(at 274.510773 -124.906447 0)
			(layer "F.Fab")
			(hide yes)
			(effects
				(font
					(size 1 1)
					(thickness 0.15)
				)
			)
		)
		(property "MPN" "LTST-C190GKT"
			(at 274.510773 -124.906447 0)
			(layer "F.Fab")
			(hide yes)
			(effects
				(font
					(size 1 1)
					(thickness 0.15)
				)
			)
		)
		(property "Manufacturer" "Lite-On"
			(at 274.510773 -124.906447 0)
			(layer "F.Fab")
			(hide yes)
			(effects
				(font
					(size 1 1)
					(thickness 0.15)
				)
			)
		)
		(property "Public" "False"
			(at 274.510773 -124.906447 0)
			(layer "F.Fab")
			(hide yes)
			(effects
				(font
					(size 1 1)
					(thickness 0.15)
				)
			)
		)
		(sheetname "Power")
		(sheetfile "power.kicad_sch")
		(attr smd)
		(fp_line
			(start 0.22 -0.35)
			(end -0.22 -0.35)
			(stroke
				(width 0.15)
				(type solid)
			)
			(layer "F.SilkS")
		)
		(fp_line
			(start -1.18 -0.319)
			(end -1.18 0.321)
			(stroke
				(width 0.15)
				(type solid)
			)
			(layer "F.SilkS")
		)
		(fp_line
			(start 0.105328 0.001008)
			(end 0.24 0.001)
			(stroke
				(width 0.1)
				(type solid)
			)
			(layer "F.SilkS")
		)
		(fp_line
			(start -0.094672 0.001008)
			(end 0.105328 -0.198992)
			(stroke
				(width 0.1)
				(type solid)
			)
			(layer "F.SilkS")
		)
		(fp_line
			(start -0.094672 0.001008)
			(end -0.24 0.001008)
			(stroke
				(width 0.1)
				(type solid)
			)
			(layer "F.SilkS")
		)
		(fp_line
			(start 0.105328 0.201008)
			(end 0.105328 -0.198992)
			(stroke
				(width 0.1)
				(type solid)
			)
			(layer "F.SilkS")
		)
		(fp_line
			(start 0.105328 0.201008)
			(end -0.094672 0.001008)
			(stroke
				(width 0.1)
				(type solid)
			)
			(layer "F.SilkS")
		)
		(fp_line
			(start -0.094672 0.201008)
			(end -0.094672 -0.198992)
			(stroke
				(width 0.1)
				(type solid)
			)
			(layer "F.SilkS")
		)
		(fp_line
			(start 0.22 0.35)
			(end -0.22 0.35)
			(stroke
				(width 0.15)
				(type solid)
			)
			(layer "F.SilkS")
		)
		(fp_rect
			(start 1.25 0.65)
			(end -1.25 -0.65)
			(stroke
				(width 0.05)
				(type solid)
			)
			(fill no)
			(layer "F.CrtYd")
		)
		(fp_line
			(start 0.201 -0.202)
			(end -0.101 0)
			(stroke
				(width 0.15)
				(type solid)
			)
			(layer "F.Fab")
		)
		(fp_line
			(start -0.199 -0.202)
			(end -0.199 0.1)
			(stroke
				(width 0.15)
				(type solid)
			)
			(layer "F.Fab")
		)
		(fp_line
			(start 0.599 0)
			(end 0.201 0)
			(stroke
				(width 0.15)
				(type solid)
			)
			(layer "F.Fab")
		)
		(fp_line
			(start 0.201 0)
			(end 0.201 -0.202)
			(stroke
				(width 0.15)
				(type solid)
			)
			(layer "F.Fab")
		)
		(fp_line
			(start -0.101 0)
			(end 0.201 0.2)
			(stroke
				(width 0.15)
				(type solid)
			)
			(layer "F.Fab")
		)
		(fp_line
			(start -0.199 0)
			(end -0.597 0)
			(stroke
				(width 0.15)
				(type solid)
			)
			(layer "F.Fab")
		)
		(fp_line
			(start 0.201 0.2)
			(end 0.201 0)
			(stroke
				(width 0.15)
				(type solid)
			)
			(layer "F.Fab")
		)
		(fp_line
			(start -0.199 0.2)
			(end -0.199 0.1)
			(stroke
				(width 0.15)
				(type solid)
			)
			(layer "F.Fab")
		)
		(fp_rect
			(start 0.848 0.4)
			(end -0.85 -0.402)
			(stroke
				(width 0.15)
				(type solid)
			)
			(fill no)
			(layer "F.Fab")
		)
		(pad "1" smd roundrect
			(at -0.7 0 270)
			(size 0.8 1)
			(layers "F.Cu" "F.Mask" "F.Paste")
			(roundrect_rratio 0.2)
			(net 980 "Net-(D27-C)")
			(pinfunction "C")
			(pintype "passive")
			(teardrops
				(best_length_ratio 0.2)
				(max_length 1)
				(best_width_ratio 0.9)
				(max_width 2)
				(curved_edges yes)
				(filter_ratio 0.9)
				(enabled yes)
				(allow_two_segments yes)
				(prefer_zone_connections yes)
			)
		)
		(pad "2" smd roundrect
			(at 0.7 0 270)
			(size 0.8 1)
			(layers "F.Cu" "F.Mask" "F.Paste")
			(roundrect_rratio 0.2)
			(net 62 "+12V_AON")
			(pinfunction "A")
			(pintype "passive")
			(teardrops
				(best_length_ratio 0.2)
				(max_length 1)
				(best_width_ratio 0.9)
				(max_width 2)
				(curved_edges yes)
				(filter_ratio 0.9)
				(enabled yes)
				(allow_two_segments yes)
				(prefer_zone_connections yes)
			)
		)
	)
	(footprint "antmicro-footprints:Spacer_Drill3.7mm_H5mm_9774050151R"
		(layer "F.Cu")
		(at 161.93 167.8 90)
		(descr "Spacer M=3 h=5mm fi=5.1mm")
		(property "Reference" "H6"
			(at 0 -3.2 90)
			(layer "F.SilkS")
			(hide yes)
			(effects
				(font
					(size 0.7 0.7)
					(thickness 0.15)
				)
				(justify left bottom)
			)
		)
		(property "Value" "Spacer_Drill3.7mm_H5mm_9774050151R"
			(at 0 4 90)
			(layer "F.Fab")
			(effects
				(font
					(size 0.7 0.7)
					(thickness 0.15)
				)
				(justify left bottom)
			)
		)
		(property "Datasheet" "https://www.we-online.com/catalog/datasheet/9774050151.pdf"
			(at 0 0 90)
			(layer "F.Fab")
			(hide yes)
			(effects
				(font
					(size 1.27 1.27)
					(thickness 0.15)
				)
			)
		)
		(property "Author" "Antmicro"
			(at 329.73 5.87 0)
			(layer "F.Fab")
			(hide yes)
			(effects
				(font
					(size 1 1)
					(thickness 0.15)
				)
			)
		)
		(property "License" "Apache-2.0"
			(at 329.73 5.87 0)
			(layer "F.Fab")
			(hide yes)
			(effects
				(font
					(size 1 1)
					(thickness 0.15)
				)
			)
		)
		(property "MPN" "9774050151R"
			(at 329.73 5.87 0)
			(layer "F.Fab")
			(hide yes)
			(effects
				(font
					(size 1 1)
					(thickness 0.15)
				)
			)
		)
		(property "Manufacturer" "Würth Elektronik"
			(at 329.73 5.87 0)
			(layer "F.Fab")
			(hide yes)
			(effects
				(font
					(size 1 1)
					(thickness 0.15)
				)
			)
		)
		(sheetname "Com Express 7 Interfaces")
		(sheetfile "com_express_7_interfaces.kicad_sch")
		(solder_paste_margin_ratio -1)
		(attr smd)
		(fp_circle
			(center 0 0)
			(end 3.05 0)
			(stroke
				(width 0.05)
				(type solid)
			)
			(fill no)
			(layer "F.CrtYd")
		)
		(fp_circle
			(center 0 0)
			(end 2.6 0)
			(stroke
				(width 0.15)
				(type solid)
			)
			(fill no)
			(layer "F.Fab")
		)
		(pad "" smd custom
			(at -1.7 -1.7 90)
			(size 0.62 0.62)
			(layers "F.Paste")
			(thermal_bridge_angle 90)
			(options
				(clearance outline)
				(anchor circle)
			)
			(primitives
				(gr_arc
					(start -0.250195 1.279127)
					(mid 0.285453 0.294389)
					(end 1.266786 -0.24747)
					(width 0.2)
				)
				(gr_arc
					(start -0.34334 1.279127)
					(mid 0.218448 0.232561)
					(end 1.259603 -0.339191)
					(width 0.2)
				)
				(gr_arc
					(start -0.436309 1.279127)
					(mid 0.152481 0.169693)
					(end 1.255279 -0.431435)
					(width 0.2)
				)
				(gr_arc
					(start -0.529126 1.279127)
					(mid 0.087542 0.105784)
					(end 1.253811 -0.524161)
					(width 0.2)
				)
				(gr_arc
					(start -0.621807 1.279127)
					(mid 0.0309 0.033527)
					(end 1.275473 -0.621136)
					(width 0.2)
				)
				(gr_arc
					(start -0.71437 1.279127)
					(mid -0.037758 -0.026651)
					(end 1.263664 -0.711602)
					(width 0.2)
				)
				(gr_arc
					(start -0.806826 1.279127)
					(mid -0.105837 -0.087395)
					(end 1.253435 -0.802342)
					(width 0.2)
				)
				(gr_arc
					(start -0.899187 1.279127)
					(mid -0.165236 -0.156885)
					(end 1.267475 -0.897258)
					(width 0.2)
				)
				(gr_arc
					(start -0.991463 1.279127)
					(mid -0.228522 -0.222449)
					(end 1.270645 -0.990112)
					(width 0.2)
				)
				(gr_arc
					(start -1.083663 1.279127)
					(mid -0.294507 -0.285313)
					(end 1.266278 -1.081674)
					(width 0.2)
				)
				(gr_line
					(start 1.279127 -0.250195)
					(end 1.279127 -1.083663)
					(width 0.2)
				)
				(gr_line
					(start -0.250195 1.279127)
					(end -1.083663 1.279127)
					(width 0.2)
				)
			)
			(teardrops
				(best_length_ratio 0.2)
				(max_length 1)
				(best_width_ratio 0.9)
				(max_width 2)
				(curved_edges yes)
				(filter_ratio 0.9)
				(enabled yes)
				(allow_two_segments yes)
				(prefer_zone_connections yes)
			)
		)
		(pad "" smd custom
			(at -1.7 1.7 180)
			(size 0.62 0.62)
			(layers "F.Paste")
			(thermal_bridge_angle 90)
			(options
				(clearance outline)
				(anchor circle)
			)
			(primitives
				(gr_arc
					(start -0.250195 1.279127)
					(mid 0.285453 0.294389)
					(end 1.266786 -0.24747)
					(width 0.2)
				)
				(gr_arc
					(start -0.34334 1.279127)
					(mid 0.218448 0.232561)
					(end 1.259603 -0.339191)
					(width 0.2)
				)
				(gr_arc
					(start -0.436309 1.279127)
					(mid 0.152481 0.169693)
					(end 1.255279 -0.431435)
					(width 0.2)
				)
				(gr_arc
					(start -0.529126 1.279127)
					(mid 0.087542 0.105784)
					(end 1.253811 -0.524161)
					(width 0.2)
				)
				(gr_arc
					(start -0.621807 1.279127)
					(mid 0.0309 0.033527)
					(end 1.275473 -0.621136)
					(width 0.2)
				)
				(gr_arc
					(start -0.71437 1.279127)
					(mid -0.037758 -0.026651)
					(end 1.263664 -0.711602)
					(width 0.2)
				)
				(gr_arc
					(start -0.806826 1.279127)
					(mid -0.105837 -0.087395)
					(end 1.253435 -0.802342)
					(width 0.2)
				)
				(gr_arc
					(start -0.899187 1.279127)
					(mid -0.165236 -0.156885)
					(end 1.267475 -0.897258)
					(width 0.2)
				)
				(gr_arc
					(start -0.991463 1.279127)
					(mid -0.228522 -0.222449)
					(end 1.270645 -0.990112)
					(width 0.2)
				)
				(gr_arc
					(start -1.083663 1.279127)
					(mid -0.294507 -0.285313)
					(end 1.266278 -1.081674)
					(width 0.2)
				)
				(gr_line
					(start 1.279127 -0.250195)
					(end 1.279127 -1.083663)
					(width 0.2)
				)
				(gr_line
					(start -0.250195 1.279127)
					(end -1.083663 1.279127)
					(width 0.2)
				)
			)
			(teardrops
				(best_length_ratio 0.2)
				(max_length 1)
				(best_width_ratio 0.9)
				(max_width 2)
				(curved_edges yes)
				(filter_ratio 0.9)
				(enabled yes)
				(allow_two_segments yes)
				(prefer_zone_connections yes)
			)
		)
		(pad "" smd custom
			(at 1.7 -1.7)
			(size 0.62 0.62)
			(layers "F.Paste")
			(thermal_bridge_angle 90)
			(options
				(clearance outline)
				(anchor circle)
			)
			(primitives
				(gr_arc
					(start -0.250195 1.279127)
					(mid 0.285453 0.294389)
					(end 1.266786 -0.24747)
					(width 0.2)
				)
				(gr_arc
					(start -0.34334 1.279127)
					(mid 0.218448 0.232561)
					(end 1.259603 -0.339191)
					(width 0.2)
				)
				(gr_arc
					(start -0.436309 1.279127)
					(mid 0.152481 0.169693)
					(end 1.255279 -0.431435)
					(width 0.2)
				)
				(gr_arc
					(start -0.529126 1.279127)
					(mid 0.087542 0.105784)
					(end 1.253811 -0.524161)
					(width 0.2)
				)
				(gr_arc
					(start -0.621807 1.279127)
					(mid 0.0309 0.033527)
					(end 1.275473 -0.621136)
					(width 0.2)
				)
				(gr_arc
					(start -0.71437 1.279127)
					(mid -0.037758 -0.026651)
					(end 1.263664 -0.711602)
					(width 0.2)
				)
				(gr_arc
					(start -0.806826 1.279127)
					(mid -0.105837 -0.087395)
					(end 1.253435 -0.802342)
					(width 0.2)
				)
				(gr_arc
					(start -0.899187 1.279127)
					(mid -0.165236 -0.156885)
					(end 1.267475 -0.897258)
					(width 0.2)
				)
				(gr_arc
					(start -0.991463 1.279127)
					(mid -0.228522 -0.222449)
					(end 1.270645 -0.990112)
					(width 0.2)
				)
				(gr_arc
					(start -1.083663 1.279127)
					(mid -0.294507 -0.285313)
					(end 1.266278 -1.081674)
					(width 0.2)
				)
				(gr_line
					(start 1.279127 -0.250195)
					(end 1.279127 -1.083663)
					(width 0.2)
				)
				(gr_line
					(start -0.250195 1.279127)
					(end -1.083663 1.279127)
					(width 0.2)
				)
			)
			(teardrops
				(best_length_ratio 0.2)
				(max_length 1)
				(best_width_ratio 0.9)
				(max_width 2)
				(curved_edges yes)
				(filter_ratio 0.9)
				(enabled yes)
				(allow_two_segments yes)
				(prefer_zone_connections yes)
			)
		)
		(pad "" smd custom
			(at 1.7 1.7 270)
			(size 0.62 0.62)
			(layers "F.Paste")
			(thermal_bridge_angle 90)
			(options
				(clearance outline)
				(anchor circle)
			)
			(primitives
				(gr_arc
					(start -0.250195 1.279127)
					(mid 0.285453 0.294389)
					(end 1.266786 -0.24747)
					(width 0.2)
				)
				(gr_arc
					(start -0.34334 1.279127)
					(mid 0.218448 0.232561)
					(end 1.259603 -0.339191)
					(width 0.2)
				)
				(gr_arc
					(start -0.436309 1.279127)
					(mid 0.152481 0.169693)
					(end 1.255279 -0.431435)
					(width 0.2)
				)
				(gr_arc
					(start -0.529126 1.279127)
					(mid 0.087542 0.105784)
					(end 1.253811 -0.524161)
					(width 0.2)
				)
				(gr_arc
					(start -0.621807 1.279127)
					(mid 0.0309 0.033527)
					(end 1.275473 -0.621136)
					(width 0.2)
				)
				(gr_arc
					(start -0.71437 1.279127)
					(mid -0.037758 -0.026651)
					(end 1.263664 -0.711602)
					(width 0.2)
				)
				(gr_arc
					(start -0.806826 1.279127)
					(mid -0.105837 -0.087395)
					(end 1.253435 -0.802342)
					(width 0.2)
				)
				(gr_arc
					(start -0.899187 1.279127)
					(mid -0.165236 -0.156885)
					(end 1.267475 -0.897258)
					(width 0.2)
				)
				(gr_arc
					(start -0.991463 1.279127)
					(mid -0.228522 -0.222449)
					(end 1.270645 -0.990112)
					(width 0.2)
				)
				(gr_arc
					(start -1.083663 1.279127)
					(mid -0.294507 -0.285313)
					(end 1.266278 -1.081674)
					(width 0.2)
				)
				(gr_line
					(start 1.279127 -0.250195)
					(end 1.279127 -1.083663)
					(width 0.2)
				)
				(gr_line
					(start -0.250195 1.279127)
					(end -1.083663 1.279127)
					(width 0.2)
				)
			)
			(teardrops
				(best_length_ratio 0.2)
				(max_length 1)
				(best_width_ratio 0.9)
				(max_width 2)
				(curved_edges yes)
				(filter_ratio 0.9)
				(enabled yes)
				(allow_two_segments yes)
				(prefer_zone_connections yes)
			)
		)
		(pad "1" thru_hole circle
			(at 0 0 90)
			(size 6 6)
			(drill 3.7)
			(layers "*.Cu" "*.Mask")
			(remove_unused_layers no)
			(net 1 "GND")
			(pintype "passive")
			(teardrops
				(best_length_ratio 0.4)
				(max_length 1)
				(best_width_ratio 0.9)
				(max_width 2)
				(curved_edges yes)
				(filter_ratio 0.9)
				(enabled yes)
				(allow_two_segments yes)
				(prefer_zone_connections yes)
			)
		)
	)
	(footprint "antmicro-footprints:C_0402_1005Metric"
		(layer "F.Cu")
		(at 192.219362 138.815246 -45)
		(descr "Capacitor SMD 0402")
		(tags "capacitor SMD 0402")
		(property "Reference" "C117"
			(at 3.864615 -0.381761 135)
			(layer "F.SilkS")
			(effects
				(font
					(size 0.7 0.7)
					(thickness 0.15)
				)
				(justify right top)
			)
		)
		(property "Value" "C_100n_0402"
			(at -1.022927 2.155213 135)
			(layer "F.Fab")
			(effects
				(font
					(size 0.7 0.7)
					(thickness 0.15)
				)
				(justify right top)
			)
		)
		(property "Datasheet" "https://www.murata.com/products/productdetail?partno=GRM155R61H104KE14%23"
			(at 0 0 135)
			(layer "B.Fab")
			(hide yes)
			(effects
				(font
					(size 1.27 1.27)
					(thickness 0.15)
				)
				(justify mirror)
			)
		)
		(property "Author" "Antmicro"
			(at 55.668 -328.634 45)
			(layer "F.Fab")
			(hide yes)
			(effects
				(font
					(size 1 1)
					(thickness 0.15)
				)
			)
		)
		(property "Dielectric" "X5R"
			(at 55.668 -328.634 45)
			(layer "F.Fab")
			(hide yes)
			(effects
				(font
					(size 1 1)
					(thickness 0.15)
				)
			)
		)
		(property "License" "Apache-2.0"
			(at 55.668 -328.634 45)
			(layer "F.Fab")
			(hide yes)
			(effects
				(font
					(size 1 1)
					(thickness 0.15)
				)
			)
		)
		(property "MPN" "GRM155R61H104KE14D"
			(at 55.668 -328.634 45)
			(layer "F.Fab")
			(hide yes)
			(effects
				(font
					(size 1 1)
					(thickness 0.15)
				)
			)
		)
		(property "Manufacturer" "Murata"
			(at 55.668 -328.634 45)
			(layer "F.Fab")
			(hide yes)
			(effects
				(font
					(size 1 1)
					(thickness 0.15)
				)
			)
		)
		(property "Public" "False"
			(at 55.668 -328.634 45)
			(layer "F.Fab")
			(hide yes)
			(effects
				(font
					(size 1 1)
					(thickness 0.15)
				)
			)
		)
		(property "Val" "100n"
			(at 55.668 -328.634 45)
			(layer "F.Fab")
			(hide yes)
			(effects
				(font
					(size 1 1)
					(thickness 0.15)
				)
			)
		)
		(property "Voltage" "50V"
			(at 55.668 -328.634 45)
			(layer "F.Fab")
			(hide yes)
			(effects
				(font
					(size 1 1)
					(thickness 0.15)
				)
			)
		)
		(sheetname "PCIe redriver")
		(sheetfile "pcie_redriver.kicad_sch")
		(attr smd)
		(fp_poly
			(pts
				(xy -0.925 -0.47) (xy 0.925 -0.47) (xy 0.925 0.47) (xy -0.925 0.47)
			)
			(stroke
				(width 0.05)
				(type default)
			)
			(fill no)
			(layer "F.CrtYd")
		)
		(fp_line
			(start -0.494 0.248)
			(end -0.494 -0.25)
			(stroke
				(width 0.15)
				(type solid)
			)
			(layer "F.Fab")
		)
		(fp_line
			(start -0.494 -0.25)
			(end 0.504 -0.25)
			(stroke
				(width 0.15)
				(type solid)
			)
			(layer "F.Fab")
		)
		(fp_line
			(start 0.504 0.248)
			(end -0.494 0.248)
			(stroke
				(width 0.15)
				(type solid)
			)
			(layer "F.Fab")
		)
		(fp_line
			(start 0.504 -0.25)
			(end 0.504 0.248)
			(stroke
				(width 0.15)
				(type solid)
			)
			(layer "F.Fab")
		)
		(pad "1" smd roundrect
			(at -0.48 0 315)
			(size 0.59 0.64)
			(layers "F.Cu" "F.Mask" "F.Paste")
			(roundrect_rratio 0.25)
			(net 1 "GND")
			(pintype "passive")
			(teardrops
				(best_length_ratio 0.2)
				(max_length 1)
				(best_width_ratio 0.9)
				(max_width 2)
				(curved_edges yes)
				(filter_ratio 0.9)
				(enabled yes)
				(allow_two_segments yes)
				(prefer_zone_connections yes)
			)
		)
		(pad "2" smd roundrect
			(at 0.48 0 315)
			(size 0.59 0.64)
			(layers "F.Cu" "F.Mask" "F.Paste")
			(roundrect_rratio 0.25)
			(net 2 "+3V3")
			(pintype "passive")
			(teardrops
				(best_length_ratio 0.2)
				(max_length 1)
				(best_width_ratio 0.9)
				(max_width 2)
				(curved_edges yes)
				(filter_ratio 0.9)
				(enabled yes)
				(allow_two_segments yes)
				(prefer_zone_connections yes)
			)
		)
	)
)
